FILE_TYPE = CONNECTIVITY;
{Allegro Design Entry HDL 17.2-2016 S081 (4005846) 1/11/2022}
"PAGE_NUMBER" = 62;
0"NC";
1"P5E_CPU1_PE4_TX_DP<15:0>";
2"P5E_CPU1_PE4_TX_DN<15:0>";
3"P5E_CPU1_PE4_RX_DP<15:0>";
4"P5E_CPU1_PE4_RX_DN<15:0>";
5"P5E_CPU1_PE4_RX_DN<15>";
6"P5E_CPU1_PE4_RX_DN<14>";
7"P5E_CPU1_PE4_RX_DN<13>";
8"P5E_CPU1_PE4_RX_DN<12>";
9"P5E_CPU1_PE4_RX_DN<11>";
10"P5E_CPU1_PE4_RX_DN<10>";
11"P5E_CPU1_PE4_RX_DN<9>";
12"P5E_CPU1_PE4_RX_DN<8>";
13"P5E_CPU1_PE4_RX_DN<7>";
14"P5E_CPU1_PE4_RX_DN<6>";
15"P5E_CPU1_PE4_RX_DN<5>";
16"P5E_CPU1_PE4_RX_DN<4>";
17"P5E_CPU1_PE4_RX_DN<3>";
18"P5E_CPU1_PE4_RX_DN<2>";
19"P5E_CPU1_PE4_RX_DN<1>";
20"P5E_CPU1_PE4_RX_DN<0>";
21"P5E_CPU1_PE4_RX_DP<15>";
22"P5E_CPU1_PE4_RX_DP<14>";
23"P5E_CPU1_PE4_RX_DP<13>";
24"P5E_CPU1_PE4_RX_DP<12>";
25"P5E_CPU1_PE4_RX_DP<11>";
26"P5E_CPU1_PE4_RX_DP<10>";
27"P5E_CPU1_PE4_RX_DP<9>";
28"P5E_CPU1_PE4_RX_DP<8>";
29"P5E_CPU1_PE4_RX_DP<7>";
30"P5E_CPU1_PE4_RX_DP<6>";
31"P5E_CPU1_PE4_RX_DP<5>";
32"P5E_CPU1_PE4_RX_DP<4>";
33"P5E_CPU1_PE4_RX_DP<3>";
34"P5E_CPU1_PE4_RX_DP<2>";
35"P5E_CPU1_PE4_RX_DP<1>";
36"P5E_CPU1_PE4_RX_DP<0>";
37"P5E_CPU1_PE4_TX_DN<15>";
38"P5E_CPU1_PE4_TX_DN<14>";
39"P5E_CPU1_PE4_TX_DN<13>";
40"P5E_CPU1_PE4_TX_DN<12>";
41"P5E_CPU1_PE4_TX_DN<11>";
42"P5E_CPU1_PE4_TX_DN<10>";
43"P5E_CPU1_PE4_TX_DN<9>";
44"P5E_CPU1_PE4_TX_DN<8>";
45"P5E_CPU1_PE4_TX_DN<7>";
46"P5E_CPU1_PE4_TX_DN<6>";
47"P5E_CPU1_PE4_TX_DN<5>";
48"P5E_CPU1_PE4_TX_DN<4>";
49"P5E_CPU1_PE4_TX_DN<3>";
50"P5E_CPU1_PE4_TX_DN<2>";
51"P5E_CPU1_PE4_TX_DN<1>";
52"P5E_CPU1_PE4_TX_DN<0>";
53"P5E_CPU1_PE4_TX_DP<15>";
54"P5E_CPU1_PE4_TX_DP<14>";
55"P5E_CPU1_PE4_TX_DP<13>";
56"P5E_CPU1_PE4_TX_DP<12>";
57"P5E_CPU1_PE4_TX_DP<11>";
58"P5E_CPU1_PE4_TX_DP<10>";
59"P5E_CPU1_PE4_TX_DP<9>";
60"P5E_CPU1_PE4_TX_DP<8>";
61"P5E_CPU1_PE4_TX_DP<7>";
62"P5E_CPU1_PE4_TX_DP<6>";
63"P5E_CPU1_PE4_TX_DP<5>";
64"P5E_CPU1_PE4_TX_DP<4>";
65"P5E_CPU1_PE4_TX_DP<3>";
66"P5E_CPU1_PE4_TX_DP<2>";
67"P5E_CPU1_PE4_TX_DP<1>";
68"P5E_CPU1_PE4_TX_DP<0>";
%"TAP"
"1","(-1550,3200)","2","standard","I100";
;
CDS_LIB"standard"
BODY_TYPE"PLUMBING"
HDL_TAP"TRUE";
"B \NAC \NWC"4;
"S \NAC"
BN"3"17;
%"TAP"
"1","(-1550,3150)","2","standard","I101";
;
CDS_LIB"standard"
BODY_TYPE"PLUMBING"
HDL_TAP"TRUE";
"B \NAC \NWC"4;
"S \NAC"
BN"2"18;
%"TAP"
"1","(-1550,3300)","2","standard","I102";
;
CDS_LIB"standard"
BODY_TYPE"PLUMBING"
HDL_TAP"TRUE";
"B \NAC \NWC"4;
"S \NAC"
BN"5"15;
%"TAP"
"1","(-1550,3250)","2","standard","I103";
;
CDS_LIB"standard"
BODY_TYPE"PLUMBING"
HDL_TAP"TRUE";
"B \NAC \NWC"4;
"S \NAC"
BN"4"16;
%"TAP"
"1","(-1550,3350)","2","standard","I104";
;
CDS_LIB"standard"
BODY_TYPE"PLUMBING"
HDL_TAP"TRUE";
"B \NAC \NWC"4;
"S \NAC"
BN"6"14;
%"TAP"
"1","(-1550,3450)","2","standard","I105";
;
CDS_LIB"standard"
BODY_TYPE"PLUMBING"
HDL_TAP"TRUE";
"B \NAC \NWC"4;
"S \NAC"
BN"8"12;
%"TAP"
"1","(-1550,3400)","2","standard","I106";
;
CDS_LIB"standard"
BODY_TYPE"PLUMBING"
HDL_TAP"TRUE";
"B \NAC \NWC"4;
"S \NAC"
BN"7"13;
%"TAP"
"1","(-1550,3550)","2","standard","I107";
;
CDS_LIB"standard"
BODY_TYPE"PLUMBING"
HDL_TAP"TRUE";
"B \NAC \NWC"4;
"S \NAC"
BN"10"10;
%"TAP"
"1","(-1550,3500)","2","standard","I108";
;
CDS_LIB"standard"
BODY_TYPE"PLUMBING"
HDL_TAP"TRUE";
"B \NAC \NWC"4;
"S \NAC"
BN"9"11;
%"TAP"
"1","(-1550,3600)","2","standard","I109";
;
CDS_LIB"standard"
BODY_TYPE"PLUMBING"
HDL_TAP"TRUE";
"B \NAC \NWC"4;
"S \NAC"
BN"11"9;
%"TAP"
"1","(-1550,3700)","2","standard","I110";
;
CDS_LIB"standard"
BODY_TYPE"PLUMBING"
HDL_TAP"TRUE";
"B \NAC \NWC"4;
"S \NAC"
BN"13"7;
%"TAP"
"1","(-1550,3650)","2","standard","I111";
;
CDS_LIB"standard"
BODY_TYPE"PLUMBING"
HDL_TAP"TRUE";
"B \NAC \NWC"4;
"S \NAC"
BN"12"8;
%"TAP"
"1","(-1550,3750)","2","standard","I112";
;
CDS_LIB"standard"
BODY_TYPE"PLUMBING"
HDL_TAP"TRUE";
"B \NAC \NWC"4;
"S \NAC"
BN"14"6;
%"TAP"
"1","(-1550,3800)","2","standard","I113";
;
CDS_LIB"standard"
BODY_TYPE"PLUMBING"
HDL_TAP"TRUE";
"B \NAC \NWC"4;
"S \NAC"
BN"15"5;
%"TAP"
"1","(-1550,3900)","2","standard","I114";
;
CDS_LIB"standard"
BODY_TYPE"PLUMBING"
HDL_TAP"TRUE";
"B \NAC \NWC"3;
"S \NAC"
BN"0"36;
%"TAP"
"1","(-1550,3950)","2","standard","I115";
;
CDS_LIB"standard"
BODY_TYPE"PLUMBING"
HDL_TAP"TRUE";
"B \NAC \NWC"3;
"S \NAC"
BN"1"35;
%"TAP"
"1","(-1550,4000)","2","standard","I116";
;
CDS_LIB"standard"
BODY_TYPE"PLUMBING"
HDL_TAP"TRUE";
"B \NAC \NWC"3;
"S \NAC"
BN"2"34;
%"TAP"
"1","(-1550,4050)","2","standard","I117";
;
CDS_LIB"standard"
BODY_TYPE"PLUMBING"
HDL_TAP"TRUE";
"B \NAC \NWC"3;
"S \NAC"
BN"3"33;
%"TAP"
"1","(-1550,4100)","2","standard","I118";
;
CDS_LIB"standard"
BODY_TYPE"PLUMBING"
HDL_TAP"TRUE";
"B \NAC \NWC"3;
"S \NAC"
BN"4"32;
%"TAP"
"1","(-1550,4150)","2","standard","I119";
;
CDS_LIB"standard"
BODY_TYPE"PLUMBING"
HDL_TAP"TRUE";
"B \NAC \NWC"3;
"S \NAC"
BN"5"31;
%"TAP"
"1","(-1550,4200)","2","standard","I120";
;
CDS_LIB"standard"
BODY_TYPE"PLUMBING"
HDL_TAP"TRUE";
"B \NAC \NWC"3;
"S \NAC"
BN"6"30;
%"TAP"
"1","(-1550,4250)","2","standard","I121";
;
CDS_LIB"standard"
BODY_TYPE"PLUMBING"
HDL_TAP"TRUE";
"B \NAC \NWC"3;
"S \NAC"
BN"7"29;
%"TAP"
"1","(-1550,4300)","2","standard","I122";
;
CDS_LIB"standard"
BODY_TYPE"PLUMBING"
HDL_TAP"TRUE";
"B \NAC \NWC"3;
"S \NAC"
BN"8"28;
%"TAP"
"1","(-1550,4350)","2","standard","I123";
;
CDS_LIB"standard"
BODY_TYPE"PLUMBING"
HDL_TAP"TRUE";
"B \NAC \NWC"3;
"S \NAC"
BN"9"27;
%"TAP"
"1","(-1550,4400)","2","standard","I124";
;
CDS_LIB"standard"
BODY_TYPE"PLUMBING"
HDL_TAP"TRUE";
"B \NAC \NWC"3;
"S \NAC"
BN"10"26;
%"TAP"
"1","(-1550,4450)","2","standard","I125";
;
CDS_LIB"standard"
BODY_TYPE"PLUMBING"
HDL_TAP"TRUE";
"B \NAC \NWC"3;
"S \NAC"
BN"11"25;
%"TAP"
"1","(-1550,4500)","2","standard","I126";
;
CDS_LIB"standard"
BODY_TYPE"PLUMBING"
HDL_TAP"TRUE";
"B \NAC \NWC"3;
"S \NAC"
BN"12"24;
%"TAP"
"1","(-1550,4550)","2","standard","I127";
;
CDS_LIB"standard"
BODY_TYPE"PLUMBING"
HDL_TAP"TRUE";
"B \NAC \NWC"3;
"S \NAC"
BN"13"23;
%"TAP"
"1","(-1550,4600)","2","standard","I128";
;
CDS_LIB"standard"
BODY_TYPE"PLUMBING"
HDL_TAP"TRUE";
"B \NAC \NWC"3;
"S \NAC"
BN"14"22;
%"TAP"
"1","(-1550,4650)","2","standard","I129";
;
CDS_LIB"standard"
BODY_TYPE"PLUMBING"
HDL_TAP"TRUE";
"B \NAC \NWC"3;
"S \NAC"
BN"15"21;
%"TAP"
"1","(1800,3050)","0","standard","I130";
;
CDS_LIB"standard"
BODY_TYPE"PLUMBING"
HDL_TAP"TRUE";
"B \NAC \NWC"2;
"S \NAC"
BN"0"52;
%"TAP"
"1","(1800,3150)","0","standard","I131";
;
CDS_LIB"standard"
BODY_TYPE"PLUMBING"
HDL_TAP"TRUE";
"B \NAC \NWC"2;
"S \NAC"
BN"2"50;
%"TAP"
"1","(1800,3100)","0","standard","I132";
;
CDS_LIB"standard"
BODY_TYPE"PLUMBING"
HDL_TAP"TRUE";
"B \NAC \NWC"2;
"S \NAC"
BN"1"51;
%"TAP"
"1","(1800,3200)","0","standard","I133";
;
CDS_LIB"standard"
BODY_TYPE"PLUMBING"
HDL_TAP"TRUE";
"B \NAC \NWC"2;
"S \NAC"
BN"3"49;
%"TAP"
"1","(1800,3250)","0","standard","I134";
;
CDS_LIB"standard"
BODY_TYPE"PLUMBING"
HDL_TAP"TRUE";
"B \NAC \NWC"2;
"S \NAC"
BN"4"48;
%"TAP"
"1","(1800,3300)","0","standard","I135";
;
CDS_LIB"standard"
BODY_TYPE"PLUMBING"
HDL_TAP"TRUE";
"B \NAC \NWC"2;
"S \NAC"
BN"5"47;
%"TAP"
"1","(1800,3400)","0","standard","I136";
;
CDS_LIB"standard"
BODY_TYPE"PLUMBING"
HDL_TAP"TRUE";
"B \NAC \NWC"2;
"S \NAC"
BN"7"45;
%"TAP"
"1","(1800,3350)","0","standard","I137";
;
CDS_LIB"standard"
BODY_TYPE"PLUMBING"
HDL_TAP"TRUE";
"B \NAC \NWC"2;
"S \NAC"
BN"6"46;
%"TAP"
"1","(1800,3450)","0","standard","I138";
;
CDS_LIB"standard"
BODY_TYPE"PLUMBING"
HDL_TAP"TRUE";
"B \NAC \NWC"2;
"S \NAC"
BN"8"44;
%"TAP"
"1","(1800,3550)","0","standard","I139";
;
CDS_LIB"standard"
BODY_TYPE"PLUMBING"
HDL_TAP"TRUE";
"B \NAC \NWC"2;
"S \NAC"
BN"10"42;
%"TAP"
"1","(1800,3500)","0","standard","I140";
;
CDS_LIB"standard"
BODY_TYPE"PLUMBING"
HDL_TAP"TRUE";
"B \NAC \NWC"2;
"S \NAC"
BN"9"43;
%"TAP"
"1","(1800,3700)","0","standard","I141";
;
CDS_LIB"standard"
BODY_TYPE"PLUMBING"
HDL_TAP"TRUE";
"B \NAC \NWC"2;
"S \NAC"
BN"13"39;
%"TAP"
"1","(1800,3650)","0","standard","I142";
;
CDS_LIB"standard"
BODY_TYPE"PLUMBING"
HDL_TAP"TRUE";
"B \NAC \NWC"2;
"S \NAC"
BN"12"40;
%"TAP"
"1","(1800,3600)","0","standard","I143";
;
CDS_LIB"standard"
BODY_TYPE"PLUMBING"
HDL_TAP"TRUE";
"B \NAC \NWC"2;
"S \NAC"
BN"11"41;
%"TAP"
"1","(1800,3800)","0","standard","I144";
;
CDS_LIB"standard"
BODY_TYPE"PLUMBING"
HDL_TAP"TRUE";
"B \NAC \NWC"2;
"S \NAC"
BN"15"37;
%"TAP"
"1","(1800,3750)","0","standard","I145";
;
CDS_LIB"standard"
BODY_TYPE"PLUMBING"
HDL_TAP"TRUE";
"B \NAC \NWC"2;
"S \NAC"
BN"14"38;
%"TAP"
"1","(1800,3900)","0","standard","I146";
;
CDS_LIB"standard"
BODY_TYPE"PLUMBING"
HDL_TAP"TRUE";
"B \NAC \NWC"1;
"S \NAC"
BN"0"68;
%"TAP"
"1","(1800,3950)","0","standard","I147";
;
CDS_LIB"standard"
BODY_TYPE"PLUMBING"
HDL_TAP"TRUE";
"B \NAC \NWC"1;
"S \NAC"
BN"1"67;
%"TAP"
"1","(1800,4050)","0","standard","I148";
;
CDS_LIB"standard"
BODY_TYPE"PLUMBING"
HDL_TAP"TRUE";
"B \NAC \NWC"1;
"S \NAC"
BN"3"65;
%"TAP"
"1","(1800,4000)","0","standard","I149";
;
CDS_LIB"standard"
BODY_TYPE"PLUMBING"
HDL_TAP"TRUE";
"B \NAC \NWC"1;
"S \NAC"
BN"2"66;
%"TAP"
"1","(1800,4200)","0","standard","I150";
;
CDS_LIB"standard"
BODY_TYPE"PLUMBING"
HDL_TAP"TRUE";
"B \NAC \NWC"1;
"S \NAC"
BN"6"62;
%"TAP"
"1","(1800,4150)","0","standard","I151";
;
CDS_LIB"standard"
BODY_TYPE"PLUMBING"
HDL_TAP"TRUE";
"B \NAC \NWC"1;
"S \NAC"
BN"5"63;
%"TAP"
"1","(1800,4100)","0","standard","I152";
;
CDS_LIB"standard"
BODY_TYPE"PLUMBING"
HDL_TAP"TRUE";
"B \NAC \NWC"1;
"S \NAC"
BN"4"64;
%"TAP"
"1","(1800,4250)","0","standard","I153";
;
CDS_LIB"standard"
BODY_TYPE"PLUMBING"
HDL_TAP"TRUE";
"B \NAC \NWC"1;
"S \NAC"
BN"7"61;
%"TAP"
"1","(1800,4300)","0","standard","I154";
;
CDS_LIB"standard"
BODY_TYPE"PLUMBING"
HDL_TAP"TRUE";
"B \NAC \NWC"1;
"S \NAC"
BN"8"60;
%"TAP"
"1","(1800,4450)","0","standard","I155";
;
CDS_LIB"standard"
BODY_TYPE"PLUMBING"
HDL_TAP"TRUE";
"B \NAC \NWC"1;
"S \NAC"
BN"11"57;
%"TAP"
"1","(1800,4400)","0","standard","I156";
;
CDS_LIB"standard"
BODY_TYPE"PLUMBING"
HDL_TAP"TRUE";
"B \NAC \NWC"1;
"S \NAC"
BN"10"58;
%"TAP"
"1","(1800,4350)","0","standard","I157";
;
CDS_LIB"standard"
BODY_TYPE"PLUMBING"
HDL_TAP"TRUE";
"B \NAC \NWC"1;
"S \NAC"
BN"9"59;
%"TAP"
"1","(1800,4550)","0","standard","I158";
;
CDS_LIB"standard"
BODY_TYPE"PLUMBING"
HDL_TAP"TRUE";
"B \NAC \NWC"1;
"S \NAC"
BN"13"55;
%"TAP"
"1","(1800,4500)","0","standard","I159";
;
CDS_LIB"standard"
BODY_TYPE"PLUMBING"
HDL_TAP"TRUE";
"B \NAC \NWC"1;
"S \NAC"
BN"12"56;
%"TAP"
"1","(1800,4600)","0","standard","I160";
;
CDS_LIB"standard"
BODY_TYPE"PLUMBING"
HDL_TAP"TRUE";
"B \NAC \NWC"1;
"S \NAC"
BN"14"54;
%"TAP"
"1","(1800,4650)","0","standard","I161";
;
CDS_LIB"standard"
BODY_TYPE"PLUMBING"
HDL_TAP"TRUE";
"B \NAC \NWC"1;
"S \NAC"
BN"15"53;
%"SOCKET4677_AZIF0045P001C01CS"
"21","(125,3850)","0","pure_quanta","I18";
;
PART_NUMBER"DGA^7000023"
VALUE"SOCKET4677_AZIF0045-P001C01CS"
MATERIAL"IO"
PART_TYPE"SMLF"
$LOCATION"U1"
CDS_LMAN_SYM_OUTLINE"-1050,950,1050,-950"
NEEDS_NO_SIZE"TRUE"
CDS_LIB"pure_quanta"
CDS_LOCATION"U1"
$SEC"21"
CDS_SEC"21";
"PE4_TX_DP0"
$PN"M87"68;
"PE4_TX_DP1"
$PN"N86"67;
"PE4_TX_DP2"
$PN"T87"66;
"PE4_TX_DP3"
$PN"V85"65;
"PE4_TX_DP4"
$PN"Y87"64;
"PE4_TX_DP5"
$PN"AB85"63;
"PE4_TX_DP6"
$PN"AD87"62;
"PE4_TX_DP7"
$PN"AF85"61;
"PE4_TX_DP8"
$PN"AH87"60;
"PE4_TX_DP9"
$PN"AK85"59;
"PE4_TX_DP10"
$PN"AM87"58;
"PE4_TX_DP11"
$PN"AN86"57;
"PE4_TX_DP12"
$PN"AT87"56;
"PE4_TX_DP13"
$PN"AV85"55;
"PE4_TX_DP14"
$PN"AY87"54;
"PE4_TX_DP15"
$PN"BB85"53;
"PE4_TX_DN0"
$PN"L86"52;
"PE4_TX_DN1"
$PN"P85"51;
"PE4_TX_DN2"
$PN"R86"50;
"PE4_TX_DN3"
$PN"U86"49;
"PE4_TX_DN4"
$PN"W86"48;
"PE4_TX_DN5"
$PN"AA86"47;
"PE4_TX_DN6"
$PN"AC86"46;
"PE4_TX_DN7"
$PN"AE86"45;
"PE4_TX_DN8"
$PN"AG86"44;
"PE4_TX_DN9"
$PN"AJ86"43;
"PE4_TX_DN10"
$PN"AL86"42;
"PE4_TX_DN11"
$PN"AP85"41;
"PE4_TX_DN12"
$PN"AR86"40;
"PE4_TX_DN13"
$PN"AU86"39;
"PE4_TX_DN14"
$PN"AW86"38;
"PE4_TX_DN15"
$PN"BA86"37;
"PE4_RX_DP0"
$PN"K89"36;
"PE4_RX_DP1"
$PN"N90"35;
"PE4_RX_DP2"
$PN"R90"34;
"PE4_RX_DP3"
$PN"U90"33;
"PE4_RX_DP4"
$PN"W90"32;
"PE4_RX_DP5"
$PN"AA90"31;
"PE4_RX_DP6"
$PN"AC90"30;
"PE4_RX_DP7"
$PN"AE90"29;
"PE4_RX_DP8"
$PN"AG90"28;
"PE4_RX_DP9"
$PN"AJ90"27;
"PE4_RX_DP10"
$PN"AL90"26;
"PE4_RX_DP11"
$PN"AN90"25;
"PE4_RX_DP12"
$PN"AR90"24;
"PE4_RX_DP13"
$PN"AU90"23;
"PE4_RX_DP14"
$PN"AW90"22;
"PE4_RX_DP15"
$PN"BA90"21;
"PE4_RX_DN0"
$PN"J90"20;
"PE4_RX_DN1"
$PN"P89"19;
"PE4_RX_DN2"
$PN"T91"18;
"PE4_RX_DN3"
$PN"V89"17;
"PE4_RX_DN4"
$PN"Y91"16;
"PE4_RX_DN5"
$PN"AB89"15;
"PE4_RX_DN6"
$PN"AD91"14;
"PE4_RX_DN7"
$PN"AF89"13;
"PE4_RX_DN8"
$PN"AH91"12;
"PE4_RX_DN9"
$PN"AK89"11;
"PE4_RX_DN10"
$PN"AM91"10;
"PE4_RX_DN11"
$PN"AP89"9;
"PE4_RX_DN12"
$PN"AT91"8;
"PE4_RX_DN13"
$PN"AV89"7;
"PE4_RX_DN14"
$PN"AY91"6;
"PE4_RX_DN15"
$PN"BB89"5;
%"TAP"
"1","(-1550,3050)","2","standard","I98";
;
CDS_LIB"standard"
BODY_TYPE"PLUMBING"
HDL_TAP"TRUE";
"B \NAC \NWC"4;
"S \NAC"
BN"0"20;
%"TAP"
"1","(-1550,3100)","2","standard","I99";
;
CDS_LIB"standard"
BODY_TYPE"PLUMBING"
HDL_TAP"TRUE";
"B \NAC \NWC"4;
"S \NAC"
BN"1"19;
END.
